(kicad_pcb
	(version 20241229)
	(generator "pcbnew")
	(generator_version "9.0")
	(general
		(thickness 1.6)
		(legacy_teardrops no)
	)
	(paper "A4")
	(title_block
		(title "OCuLink to PCIe adapter")
		(date "2025-06-18")
		(rev "1.0.0")
		(company "Antmicro Ltd")
		(comment 1 "www.antmicro.com")
		(comment 9 "footprints 1-3 of 159")
	)
	(layers
		(0 "F.Cu" signal)
		(4 "In1.Cu" signal)
		(6 "In2.Cu" signal)
		(2 "B.Cu" signal)
		(9 "F.Adhes" user "F.Adhesive")
		(11 "B.Adhes" user "B.Adhesive")
		(13 "F.Paste" user)
		(15 "B.Paste" user)
		(5 "F.SilkS" user "F.Silkscreen")
		(7 "B.SilkS" user "B.Silkscreen")
		(1 "F.Mask" user)
		(3 "B.Mask" user)
		(17 "Dwgs.User" user "User.Drawings")
		(19 "Cmts.User" user "User.Comments")
		(21 "Eco1.User" user "User.Eco1")
		(23 "Eco2.User" user "User.Eco2")
		(25 "Edge.Cuts" user)
		(27 "Margin" user)
		(31 "F.CrtYd" user "F.Courtyard")
		(29 "B.CrtYd" user "B.Courtyard")
		(35 "F.Fab" user)
		(33 "B.Fab" user)
	)
	(footprint "antmicro-footprints:MOLEX_39288080"
		(layer "F.Cu")
		(at 150.85 141.4 90)
		(property "Reference" "J5"
			(at -3.35 -2.777 90)
			(layer "F.SilkS")
			(effects
				(font
					(size 0.7 0.7)
					(thickness 0.15)
				)
				(justify left bottom)
			)
		)
		(property "Value" "Molex_Mini-Fit-Jr_2x4_39-28-8080"
			(at 4.49 11.365 90)
			(layer "F.Fab")
			(effects
				(font
					(size 0.7 0.7)
					(thickness 0.15)
				)
				(justify left bottom)
			)
		)
		(property "Datasheet" "https://www.molex.com/pdm_docs/sd/039288080_sd.pdf"
			(at 0 0 90)
			(layer "F.Fab")
			(hide yes)
			(effects
				(font
					(size 1.27 1.27)
					(thickness 0.15)
				)
			)
		)
		(property "Description" "Pin Header, THT, Vertical, UL94V-2, Power, Wire-to-Board, 4.2 mm, 2 Rows, 8 Contacts, Mini-fit Jr, 5566 series"
			(at 0 0 90)
			(layer "F.Fab")
			(hide yes)
			(effects
				(font
					(size 1.27 1.27)
					(thickness 0.15)
				)
			)
		)
		(property "MPN" "39-28-8080"
			(at 0 0 90)
			(unlocked yes)
			(layer "F.Fab")
			(hide yes)
			(effects
				(font
					(size 1 1)
					(thickness 0.15)
				)
			)
		)
		(property "Manufacturer" "Molex"
			(at 0 0 90)
			(unlocked yes)
			(layer "F.Fab")
			(hide yes)
			(effects
				(font
					(size 1 1)
					(thickness 0.15)
				)
			)
		)
		(property "Author" "Antmicro"
			(at 0 0 90)
			(unlocked yes)
			(layer "F.Fab")
			(hide yes)
			(effects
				(font
					(size 1 1)
					(thickness 0.15)
				)
			)
		)
		(property "License" "Apache-2.0"
			(at 0 0 90)
			(unlocked yes)
			(layer "F.Fab")
			(hide yes)
			(effects
				(font
					(size 1 1)
					(thickness 0.15)
				)
			)
		)
		(sheetname "/")
		(sheetfile "oculink-to-pcie-adapter.kicad_sch")
		(attr through_hole)
		(fp_circle
			(center 12.6 0)
			(end 13.113 0)
			(stroke
				(width 1.0262)
				(type solid)
			)
			(fill no)
			(layer "F.Mask")
		)
		(fp_circle
			(center 8.4 0)
			(end 8.913 0)
			(stroke
				(width 1.0262)
				(type solid)
			)
			(fill no)
			(layer "F.Mask")
		)
		(fp_circle
			(center 4.2 0)
			(end 4.713 0)
			(stroke
				(width 1.0262)
				(type solid)
			)
			(fill no)
			(layer "F.Mask")
		)
		(fp_circle
			(center 12.6 5.5)
			(end 13.113 5.5)
			(stroke
				(width 1.0262)
				(type solid)
			)
			(fill no)
			(layer "F.Mask")
		)
		(fp_circle
			(center 8.4 5.5)
			(end 8.913 5.5)
			(stroke
				(width 1.0262)
				(type solid)
			)
			(fill no)
			(layer "F.Mask")
		)
		(fp_circle
			(center 4.2 5.5)
			(end 4.713 5.5)
			(stroke
				(width 1.0262)
				(type solid)
			)
			(fill no)
			(layer "F.Mask")
		)
		(fp_circle
			(center 0 5.5)
			(end 0.513 5.5)
			(stroke
				(width 1.0262)
				(type solid)
			)
			(fill no)
			(layer "F.Mask")
		)
		(fp_poly
			(pts
				(xy -1.026 -1.026) (xy 1.026 -1.026) (xy 1.026 1.026) (xy -1.026 1.026)
			)
			(stroke
				(width 0.01)
				(type solid)
			)
			(fill yes)
			(layer "F.Mask")
		)
		(fp_circle
			(center 12.6 0)
			(end 13.113 0)
			(stroke
				(width 1.0262)
				(type solid)
			)
			(fill no)
			(layer "B.Mask")
		)
		(fp_circle
			(center 8.4 0)
			(end 8.913 0)
			(stroke
				(width 1.0262)
				(type solid)
			)
			(fill no)
			(layer "B.Mask")
		)
		(fp_circle
			(center 4.2 0)
			(end 4.713 0)
			(stroke
				(width 1.0262)
				(type solid)
			)
			(fill no)
			(layer "B.Mask")
		)
		(fp_circle
			(center 12.6 5.5)
			(end 13.113 5.5)
			(stroke
				(width 1.0262)
				(type solid)
			)
			(fill no)
			(layer "B.Mask")
		)
		(fp_circle
			(center 8.4 5.5)
			(end 8.913 5.5)
			(stroke
				(width 1.0262)
				(type solid)
			)
			(fill no)
			(layer "B.Mask")
		)
		(fp_circle
			(center 4.2 5.5)
			(end 4.713 5.5)
			(stroke
				(width 1.0262)
				(type solid)
			)
			(fill no)
			(layer "B.Mask")
		)
		(fp_circle
			(center 0 5.5)
			(end 0.513 5.5)
			(stroke
				(width 1.0262)
				(type solid)
			)
			(fill no)
			(layer "B.Mask")
		)
		(fp_poly
			(pts
				(xy -1.026 -1.026) (xy 1.026 -1.026) (xy 1.026 1.026) (xy -1.026 1.026)
			)
			(stroke
				(width 0.01)
				(type solid)
			)
			(fill yes)
			(layer "B.Mask")
		)
		(fp_line
			(start 0.4 -3.327)
			(end -0.4 -3.327)
			(stroke
				(width 0.15)
				(type solid)
			)
			(layer "F.SilkS")
		)
		(fp_line
			(start -0.4 -3.327)
			(end 0 -2.627)
			(stroke
				(width 0.15)
				(type solid)
			)
			(layer "F.SilkS")
		)
		(fp_line
			(start 0 -2.627)
			(end 0.4 -3.327)
			(stroke
				(width 0.15)
				(type solid)
			)
			(layer "F.SilkS")
		)
		(fp_line
			(start 15.7 -2.25)
			(end 15.7 8.75)
			(stroke
				(width 0.15)
				(type solid)
			)
			(layer "F.SilkS")
		)
		(fp_line
			(start -1.83 -2.25)
			(end 15.7 -2.25)
			(stroke
				(width 0.15)
				(type solid)
			)
			(layer "F.SilkS")
		)
		(fp_line
			(start -1.83 -2.25)
			(end -3.1 -0.98)
			(stroke
				(width 0.15)
				(type solid)
			)
			(layer "F.SilkS")
		)
		(fp_line
			(start 15.7 8.75)
			(end -3.1 8.75)
			(stroke
				(width 0.15)
				(type solid)
			)
			(layer "F.SilkS")
		)
		(fp_line
			(start -3.1 8.75)
			(end -3.1 -0.98)
			(stroke
				(width 0.15)
				(type solid)
			)
			(layer "F.SilkS")
		)
		(fp_circle
			(center 0 -3)
			(end 0.05 -3)
			(stroke
				(width 0.15)
				(type solid)
			)
			(fill yes)
			(layer "F.SilkS")
		)
		(fp_rect
			(start -3.5 -2.7)
			(end 16.1 9.1)
			(stroke
				(width 0.05)
				(type solid)
			)
			(fill no)
			(layer "F.CrtYd")
		)
		(fp_line
			(start 0.4 -3.327)
			(end -0.4 -3.327)
			(stroke
				(width 0.15)
				(type solid)
			)
			(layer "F.Fab")
		)
		(fp_line
			(start -0.4 -3.327)
			(end 0 -2.627)
			(stroke
				(width 0.15)
				(type solid)
			)
			(layer "F.Fab")
		)
		(fp_line
			(start 0 -2.627)
			(end 0.4 -3.327)
			(stroke
				(width 0.15)
				(type solid)
			)
			(layer "F.Fab")
		)
		(fp_line
			(start 15.7 -2.25)
			(end 15.7 8.75)
			(stroke
				(width 0.15)
				(type solid)
			)
			(layer "F.Fab")
		)
		(fp_line
			(start -1.83 -2.25)
			(end 15.7 -2.25)
			(stroke
				(width 0.15)
				(type solid)
			)
			(layer "F.Fab")
		)
		(fp_line
			(start -1.83 -2.25)
			(end -3.1 -0.98)
			(stroke
				(width 0.15)
				(type solid)
			)
			(layer "F.Fab")
		)
		(fp_line
			(start 15.7 8.75)
			(end -3.1 8.75)
			(stroke
				(width 0.15)
				(type solid)
			)
			(layer "F.Fab")
		)
		(fp_line
			(start -3.1 8.75)
			(end -3.1 -0.98)
			(stroke
				(width 0.15)
				(type solid)
			)
			(layer "F.Fab")
		)
		(fp_text user "License: Apache-2.0"
			(at -3.5 14.565 90)
			(layer "F.Fab")
			(effects
				(font
					(size 0.7 0.7)
					(thickness 0.15)
				)
				(justify left bottom)
			)
		)
		(fp_text user "Author: Antmicro"
			(at -3.5 16.965 90)
			(layer "F.Fab")
			(effects
				(font
					(size 0.7 0.7)
					(thickness 0.15)
				)
				(justify left bottom)
			)
		)
		(fp_text user "${REFERENCE}"
			(at -3.5 15.765 90)
			(layer "F.Fab")
			(effects
				(font
					(size 0.7 0.7)
					(thickness 0.15)
				)
				(justify left bottom)
			)
		)
		(fp_text user "PTH D1.40 +/- 0.05"
			(at -3.5 13.365 90)
			(layer "F.Fab")
			(effects
				(font
					(size 0.7 0.7)
					(thickness 0.15)
				)
				(justify left bottom)
			)
		)
		(pad "1" thru_hole rect
			(at 0 0 90)
			(size 1.9 1.9)
			(drill 1.4)
			(layers "*.Cu")
			(remove_unused_layers no)
			(net 66 "GND")
			(pinfunction "1")
			(pintype "passive")
		)
		(pad "2" thru_hole circle
			(at 4.2 0 90)
			(size 1.9 1.9)
			(drill 1.4)
			(layers "*.Cu")
			(remove_unused_layers no)
			(net 66 "GND")
			(pinfunction "2")
			(pintype "passive")
		)
		(pad "3" thru_hole circle
			(at 8.4 0 90)
			(size 1.9 1.9)
			(drill 1.4)
			(layers "*.Cu")
			(remove_unused_layers no)
			(net 66 "GND")
			(pinfunction "3")
			(pintype "passive")
		)
		(pad "4" thru_hole circle
			(at 12.6 0 90)
			(size 1.9 1.9)
			(drill 1.4)
			(layers "*.Cu")
			(remove_unused_layers no)
			(net 66 "GND")
			(pinfunction "4")
			(pintype "passive")
		)
		(pad "5" thru_hole circle
			(at 0 5.5 90)
			(size 1.9 1.9)
			(drill 1.4)
			(layers "*.Cu")
			(remove_unused_layers no)
			(net 169 "/Power/VCC_DC_CONN_2")
			(pinfunction "5")
			(pintype "passive")
		)
		(pad "6" thru_hole circle
			(at 4.2 5.5 90)
			(size 1.9 1.9)
			(drill 1.4)
			(layers "*.Cu")
			(remove_unused_layers no)
			(net 169 "/Power/VCC_DC_CONN_2")
			(pinfunction "6")
			(pintype "passive")
		)
		(pad "7" thru_hole circle
			(at 8.4 5.5 90)
			(size 1.9 1.9)
			(drill 1.4)
			(layers "*.Cu")
			(remove_unused_layers no)
			(net 169 "/Power/VCC_DC_CONN_2")
			(pinfunction "7")
			(pintype "passive")
		)
		(pad "8" thru_hole circle
			(at 12.6 5.5 90)
			(size 1.9 1.9)
			(drill 1.4)
			(layers "*.Cu")
			(remove_unused_layers no)
			(net 169 "/Power/VCC_DC_CONN_2")
			(pinfunction "8")
			(pintype "passive")
		)
	)
	(footprint "antmicro-footprints:R_0402_1005Metric"
		(layer "F.Cu")
		(at 131.719999 153.999999)
		(descr "Resistor SMD 0402")
		(tags "resistor SMD 0402")
		(property "Reference" "R12"
			(at 1.08 0.500001 180)
			(layer "F.SilkS")
			(effects
				(font
					(size 0.7 0.7)
					(thickness 0.15)
				)
				(justify left bottom)
			)
		)
		(property "Value" "R_10k_0402"
			(at -1.011843 1.772046 0)
			(layer "F.Fab")
			(effects
				(font
					(size 0.7 0.7)
					(thickness 0.15)
				)
				(justify left bottom)
			)
		)
		(property "Datasheet" "https://www.bourns.com/docs/product-datasheets/cr.pdf"
			(at 0 0 0)
			(layer "F.Fab")
			(hide yes)
			(effects
				(font
					(size 1.27 1.27)
					(thickness 0.15)
				)
			)
		)
		(property "Description" "SMD Chip Resistor, 10 kohm, ± 1%, 62.5 mW, 0402 [1005 Metric], Thick Film, General Purpose"
			(at 0 0 0)
			(layer "F.Fab")
			(hide yes)
			(effects
				(font
					(size 1.27 1.27)
					(thickness 0.15)
				)
			)
		)
		(property "MPN" "CR0402-FX-1002GLF"
			(at 0 0 0)
			(unlocked yes)
			(layer "F.Fab")
			(hide yes)
			(effects
				(font
					(size 1 1)
					(thickness 0.15)
				)
			)
		)
		(property "Manufacturer" "Bourns"
			(at 0 0 0)
			(unlocked yes)
			(layer "F.Fab")
			(hide yes)
			(effects
				(font
					(size 1 1)
					(thickness 0.15)
				)
			)
		)
		(property "License" "Apache-2.0"
			(at 0 0 0)
			(unlocked yes)
			(layer "F.Fab")
			(hide yes)
			(effects
				(font
					(size 1 1)
					(thickness 0.15)
				)
			)
		)
		(property "Author" "Antmicro"
			(at 0 0 0)
			(unlocked yes)
			(layer "F.Fab")
			(hide yes)
			(effects
				(font
					(size 1 1)
					(thickness 0.15)
				)
			)
		)
		(property "Val" "10k"
			(at 0 0 0)
			(unlocked yes)
			(layer "F.Fab")
			(hide yes)
			(effects
				(font
					(size 1 1)
					(thickness 0.15)
				)
			)
		)
		(property "Tolerance" "1%"
			(at 0 0 0)
			(unlocked yes)
			(layer "F.Fab")
			(hide yes)
			(effects
				(font
					(size 1 1)
					(thickness 0.15)
				)
			)
		)
		(sheetname "/Power/")
		(sheetfile "power.kicad_sch")
		(attr smd)
		(fp_rect
			(start -0.925 -0.47)
			(end 0.925 0.47)
			(stroke
				(width 0.05)
				(type default)
			)
			(fill no)
			(layer "F.CrtYd")
		)
		(fp_rect
			(start -0.5 -0.25)
			(end 0.5 0.25)
			(stroke
				(width 0.15)
				(type solid)
			)
			(fill no)
			(layer "F.Fab")
		)
		(fp_text user "License: Apache-2.0"
			(at -0.949999 5.169 0)
			(layer "F.Fab")
			(effects
				(font
					(size 0.7 0.7)
					(thickness 0.15)
				)
				(justify left bottom)
			)
		)
		(fp_text user "Author: Antmicro"
			(at -0.95 4.169 0)
			(layer "F.Fab")
			(effects
				(font
					(size 0.7 0.7)
					(thickness 0.15)
				)
				(justify left bottom)
			)
		)
		(fp_text user "${REFERENCE}"
			(at 0 0 0)
			(layer "F.Fab")
			(effects
				(font
					(size 0.7 0.7)
					(thickness 0.15)
				)
				(justify left bottom)
			)
		)
		(pad "1" smd roundrect
			(at -0.48 0)
			(size 0.59 0.64)
			(layers "F.Cu" "F.Mask" "F.Paste")
			(roundrect_rratio 0.25)
			(net 66 "GND")
			(pintype "passive")
		)
		(pad "2" smd roundrect
			(at 0.48 0)
			(size 0.59 0.64)
			(layers "F.Cu" "F.Mask" "F.Paste")
			(roundrect_rratio 0.25)
			(net 89 "Net-(D1-C)")
			(pintype "passive")
		)
	)
	(footprint "antmicro-footprints:C_0805_2012Metric"
		(layer "F.Cu")
		(at 103.8 115.2 -90)
		(descr "Capacitor SMD 0805")
		(tags "capacitor SMD 0805")
		(property "Reference" "C37"
			(at -1.1 1.8 90)
			(layer "F.SilkS")
			(effects
				(font
					(size 0.7 0.7)
					(thickness 0.15)
				)
				(justify right top)
			)
		)
		(property "Value" "C_10u_0805_35V"
			(at -2.055717 1.963153 90)
			(layer "F.Fab")
			(effects
				(font
					(size 0.7 0.7)
					(thickness 0.15)
				)
				(justify right top)
			)
		)
		(property "Datasheet" "https://www.murata.com/products/productdetail?partno=GRM21BR6YA106KE43%23"
			(at 0 0 90)
			(layer "F.Fab")
			(hide yes)
			(effects
				(font
					(size 1.27 1.27)
					(thickness 0.15)
				)
			)
		)
		(property "Description" "SMD Multilayer Ceramic Capacitor, 10 µF, 35 V, 0805 [2012 Metric], ± 10%, X5R, GRM Series"
			(at 0 0 90)
			(layer "F.Fab")
			(hide yes)
			(effects
				(font
					(size 1.27 1.27)
					(thickness 0.15)
				)
			)
		)
		(property "MPN" "GRM21BR6YA106KE43L"
			(at 0 0 270)
			(unlocked yes)
			(layer "F.Fab")
			(hide yes)
			(effects
				(font
					(size 1 1)
					(thickness 0.15)
				)
			)
		)
		(property "Manufacturer" "Murata"
			(at 0 0 270)
			(unlocked yes)
			(layer "F.Fab")
			(hide yes)
			(effects
				(font
					(size 1 1)
					(thickness 0.15)
				)
			)
		)
		(property "License" "Apache-2.0"
			(at 0 0 270)
			(unlocked yes)
			(layer "F.Fab")
			(hide yes)
			(effects
				(font
					(size 1 1)
					(thickness 0.15)
				)
			)
		)
		(property "Author" "Antmicro"
			(at 0 0 270)
			(unlocked yes)
			(layer "F.Fab")
			(hide yes)
			(effects
				(font
					(size 1 1)
					(thickness 0.15)
				)
			)
		)
		(property "Val" "10u"
			(at 0 0 270)
			(unlocked yes)
			(layer "F.Fab")
			(hide yes)
			(effects
				(font
					(size 1 1)
					(thickness 0.15)
				)
			)
		)
		(property "Voltage" "35V"
			(at 0 0 270)
			(unlocked yes)
			(layer "F.Fab")
			(hide yes)
			(effects
				(font
					(size 1 1)
					(thickness 0.15)
				)
			)
		)
		(property "Dielectric" ""
			(at 0 0 270)
			(unlocked yes)
			(layer "F.Fab")
			(hide yes)
			(effects
				(font
					(size 1 1)
					(thickness 0.15)
				)
			)
		)
		(property "Public" "False"
			(at 0 0 270)
			(unlocked yes)
			(layer "F.Fab")
			(hide yes)
			(effects
				(font
					(size 1 1)
					(thickness 0.15)
				)
			)
		)
		(sheetname "/PCIe-connector/")
		(sheetfile "pcie-connector.kicad_sch")
		(attr smd)
		(fp_line
			(start -0.3 0.7)
			(end 0.3 0.7)
			(stroke
				(width 0.15)
				(type solid)
			)
			(layer "F.SilkS")
		)
		(fp_line
			(start -0.3 -0.7)
			(end 0.3 -0.7)
			(stroke
				(width 0.15)
				(type solid)
			)
			(layer "F.SilkS")
		)
		(fp_rect
			(start 1.95 -0.9)
			(end -1.95 0.9)
			(stroke
				(width 0.05)
				(type default)
			)
			(fill no)
			(layer "F.CrtYd")
		)
		(fp_rect
			(start -0.95 -0.675)
			(end 0.95 0.675)
			(stroke
				(width 0.15)
				(type solid)
			)
			(fill no)
			(layer "F.Fab")
		)
		(fp_text user "Author: Antmicro"
			(at -1.9 5.947 90)
			(layer "F.Fab")
			(effects
				(font
					(size 0.7 0.7)
					(thickness 0.15)
				)
				(justify right top)
			)
		)
		(fp_text user "License: Apache-2.0"
			(at -1.9 4.947 90)
			(layer "F.Fab")
			(effects
				(font
					(size 0.7 0.7)
					(thickness 0.15)
				)
				(justify right top)
			)
		)
		(fp_text user "${REFERENCE}"
			(at 0 0 90)
			(layer "F.Fab")
			(effects
				(font
					(size 0.7 0.7)
					(thickness 0.15)
				)
				(justify right top)
			)
		)
		(pad "1" smd roundrect
			(at -1.1 0 270)
			(size 1.2 1.3)
			(layers "F.Cu" "F.Mask" "F.Paste")
			(roundrect_rratio 0.25)
			(net 134 "+3V3")
			(pintype "passive")
		)
		(pad "2" smd roundrect
			(at 1.1 0 270)
			(size 1.2 1.3)
			(layers "F.Cu" "F.Mask" "F.Paste")
			(roundrect_rratio 0.25)
			(net 66 "GND")
			(pintype "passive")
		)
	)
)
